(kicad_pcb
	(version 20260206)
	(generator "pcbnew")
	(generator_version "10.0")
	(general
		(thickness 1.6)
		(legacy_teardrops no)
	)
	(paper "A4")
	(title_block
		(title "01162023_DA0F0TEBIF0_F0T_Expander_BD_F_brd_V02_OCP.brd")
		(comment 1 "Grand Teton / footprints 6417-6422 of 9728")
	)
	(layers
		(0 "F.Cu" signal "TOP")
		(4 "In1.Cu" signal "GND")
		(6 "In2.Cu" signal "VCC")
		(8 "In3.Cu" signal "VCC1")
		(10 "In4.Cu" signal "GND1")
		(12 "In5.Cu" signal "IN1")
		(14 "In6.Cu" signal "GND2")
		(16 "In7.Cu" signal "IN2")
		(18 "In8.Cu" signal "GND3")
		(20 "In9.Cu" signal "IN3")
		(22 "In10.Cu" signal "GND4")
		(24 "In11.Cu" signal "IN4")
		(26 "In12.Cu" signal "GND5")
		(28 "In13.Cu" signal "IN5")
		(30 "In14.Cu" signal "GND6")
		(32 "In15.Cu" signal "IN6")
		(34 "In16.Cu" signal "GND7")
		(2 "B.Cu" signal "BOTTOM")
		(9 "F.Adhes" user "F.Adhesive")
		(11 "B.Adhes" user "B.Adhesive")
		(13 "F.Paste" user "Package Geometry/Pastemask Top")
		(15 "B.Paste" user "Package Geometry/Pastemask Bottom")
		(5 "F.SilkS" user "Ref Des/Silkscreen Top")
		(7 "B.SilkS" user "Ref Des/Silkscreen Bottom")
		(1 "F.Mask" user "Board Geometry/Soldermask Top")
		(3 "B.Mask" user "Board Geometry/Soldermask Bottom")
		(17 "Dwgs.User" user "User.Drawings")
		(19 "Cmts.User" user "User.Comments")
		(21 "Eco1.User" user "User.Eco1")
		(23 "Eco2.User" user "User.Eco2")
		(25 "Edge.Cuts" user "Board Geometry/Outline")
		(27 "Margin" user)
		(31 "F.CrtYd" user "Package Geometry/Place Bound Top")
		(29 "B.CrtYd" user "Package Geometry/Place Bound Bottom")
		(35 "F.Fab" user "Ref Des/Assembly Top")
		(33 "B.Fab" user "Ref Des/Assembly Bottom")
	)
	(footprint ""
		(layer "F.Cu")
		(at 375.122694 -311.156604 -90)
		(property "Reference" "R1461"
			(at 0 0 270)
			(layer "F.SilkS")
			(hide yes)
			(effects
				(font
					(size 1.27 1.27)
				)
			)
		)
		(property "Value" ""
			(at 0 0 270)
			(layer "F.Fab")
			(effects
				(font
					(size 1.27 1.27)
				)
			)
		)
		(duplicate_pad_numbers_are_jumpers no)
		(fp_line
			(start -0.7874 0.4064)
			(end -0.7874 -0.4064)
			(stroke
				(width 0.1524)
				(type default)
			)
			(layer "F.SilkS")
		)
		(fp_line
			(start 0.7874 0.4064)
			(end -0.7874 0.4064)
			(stroke
				(width 0.1524)
				(type default)
			)
			(layer "F.SilkS")
		)
		(fp_line
			(start -0.7874 -0.4064)
			(end 0.7874 -0.4064)
			(stroke
				(width 0.1524)
				(type default)
			)
			(layer "F.SilkS")
		)
		(fp_line
			(start 0.7874 -0.4064)
			(end 0.7874 0.4064)
			(stroke
				(width 0.1524)
				(type default)
			)
			(layer "F.SilkS")
		)
		(fp_line
			(start -0.67945 0.3048)
			(end -0.67945 -0.305054)
			(stroke
				(width 0.1)
				(type default)
			)
			(layer "F.Fab")
		)
		(fp_line
			(start -0.12065 0.3048)
			(end -0.67945 0.3048)
			(stroke
				(width 0.1)
				(type default)
			)
			(layer "F.Fab")
		)
		(fp_line
			(start 0.120396 0.3048)
			(end 0.120396 0.2794)
			(stroke
				(width 0.1)
				(type default)
			)
			(layer "F.Fab")
		)
		(fp_line
			(start 0.67945 0.3048)
			(end 0.120396 0.3048)
			(stroke
				(width 0.1)
				(type default)
			)
			(layer "F.Fab")
		)
		(fp_line
			(start -0.12065 0.2794)
			(end -0.12065 0.3048)
			(stroke
				(width 0.1)
				(type default)
			)
			(layer "F.Fab")
		)
		(fp_line
			(start 0.120396 0.2794)
			(end -0.12065 0.2794)
			(stroke
				(width 0.1)
				(type default)
			)
			(layer "F.Fab")
		)
		(fp_line
			(start -0.12065 -0.2794)
			(end 0.12065 -0.2794)
			(stroke
				(width 0.1)
				(type default)
			)
			(layer "F.Fab")
		)
		(fp_line
			(start 0.12065 -0.2794)
			(end 0.12065 -0.3048)
			(stroke
				(width 0.1)
				(type default)
			)
			(layer "F.Fab")
		)
		(fp_line
			(start 0.12065 -0.3048)
			(end 0.67945 -0.3048)
			(stroke
				(width 0.1)
				(type default)
			)
			(layer "F.Fab")
		)
		(fp_line
			(start 0.67945 -0.3048)
			(end 0.67945 0.3048)
			(stroke
				(width 0.1)
				(type default)
			)
			(layer "F.Fab")
		)
		(fp_line
			(start -0.67945 -0.305054)
			(end -0.12065 -0.305054)
			(stroke
				(width 0.1)
				(type default)
			)
			(layer "F.Fab")
		)
		(fp_line
			(start -0.12065 -0.305054)
			(end -0.12065 -0.2794)
			(stroke
				(width 0.1)
				(type default)
			)
			(layer "F.Fab")
		)
		(pad "1" smd circle
			(at -0.40005 0 270)
			(size 0 0)
			(layers "F.Cu" "F.Mask" "F.Paste")
			(net "PU_PEX3_TR_TCK")
		)
		(pad "2" smd circle
			(at 0.40005 0 270)
			(size 0 0)
			(layers "F.Cu" "F.Mask" "F.Paste")
			(net "P1V8_PEX")
		)
	)
	(footprint ""
		(layer "F.Cu")
		(at 78.243684 -43.85691)
		(property "Reference" "R531"
			(at 0 0 0)
			(layer "F.SilkS")
			(hide yes)
			(effects
				(font
					(size 1.27 1.27)
				)
			)
		)
		(property "Value" ""
			(at 0 0 0)
			(layer "F.Fab")
			(effects
				(font
					(size 1.27 1.27)
				)
			)
		)
		(duplicate_pad_numbers_are_jumpers no)
		(fp_line
			(start -0.7874 -0.4064)
			(end 0.7874 -0.4064)
			(stroke
				(width 0.1524)
				(type default)
			)
			(layer "F.SilkS")
		)
		(fp_line
			(start -0.7874 0.4064)
			(end -0.7874 -0.4064)
			(stroke
				(width 0.1524)
				(type default)
			)
			(layer "F.SilkS")
		)
		(fp_line
			(start 0.7874 -0.4064)
			(end 0.7874 0.4064)
			(stroke
				(width 0.1524)
				(type default)
			)
			(layer "F.SilkS")
		)
		(fp_line
			(start 0.7874 0.4064)
			(end -0.7874 0.4064)
			(stroke
				(width 0.1524)
				(type default)
			)
			(layer "F.SilkS")
		)
		(fp_line
			(start -0.67945 -0.305054)
			(end -0.12065 -0.305054)
			(stroke
				(width 0.1)
				(type default)
			)
			(layer "F.Fab")
		)
		(fp_line
			(start -0.67945 0.3048)
			(end -0.67945 -0.305054)
			(stroke
				(width 0.1)
				(type default)
			)
			(layer "F.Fab")
		)
		(fp_line
			(start -0.12065 -0.305054)
			(end -0.12065 -0.2794)
			(stroke
				(width 0.1)
				(type default)
			)
			(layer "F.Fab")
		)
		(fp_line
			(start -0.12065 -0.2794)
			(end 0.12065 -0.2794)
			(stroke
				(width 0.1)
				(type default)
			)
			(layer "F.Fab")
		)
		(fp_line
			(start -0.12065 0.2794)
			(end -0.12065 0.3048)
			(stroke
				(width 0.1)
				(type default)
			)
			(layer "F.Fab")
		)
		(fp_line
			(start -0.12065 0.3048)
			(end -0.67945 0.3048)
			(stroke
				(width 0.1)
				(type default)
			)
			(layer "F.Fab")
		)
		(fp_line
			(start 0.120396 0.2794)
			(end -0.12065 0.2794)
			(stroke
				(width 0.1)
				(type default)
			)
			(layer "F.Fab")
		)
		(fp_line
			(start 0.120396 0.3048)
			(end 0.120396 0.2794)
			(stroke
				(width 0.1)
				(type default)
			)
			(layer "F.Fab")
		)
		(fp_line
			(start 0.12065 -0.3048)
			(end 0.67945 -0.3048)
			(stroke
				(width 0.1)
				(type default)
			)
			(layer "F.Fab")
		)
		(fp_line
			(start 0.12065 -0.2794)
			(end 0.12065 -0.3048)
			(stroke
				(width 0.1)
				(type default)
			)
			(layer "F.Fab")
		)
		(fp_line
			(start 0.67945 -0.3048)
			(end 0.67945 0.3048)
			(stroke
				(width 0.1)
				(type default)
			)
			(layer "F.Fab")
		)
		(fp_line
			(start 0.67945 0.3048)
			(end 0.120396 0.3048)
			(stroke
				(width 0.1)
				(type default)
			)
			(layer "F.Fab")
		)
		(pad "1" smd circle
			(at -0.40005 0)
			(size 0 0)
			(layers "F.Cu" "F.Mask" "F.Paste")
			(net "SSD2_ADC_A1")
		)
		(pad "2" smd circle
			(at 0.40005 0)
			(size 0 0)
			(layers "F.Cu" "F.Mask" "F.Paste")
			(net "GND")
		)
	)
	(footprint ""
		(layer "F.Cu")
		(at 112.311942 -109.626654 180)
		(property "Reference" "R944"
			(at 0 0 180)
			(layer "F.SilkS")
			(hide yes)
			(effects
				(font
					(size 1.27 1.27)
				)
			)
		)
		(property "Value" ""
			(at 0 0 180)
			(layer "F.Fab")
			(effects
				(font
					(size 1.27 1.27)
				)
			)
		)
		(duplicate_pad_numbers_are_jumpers no)
		(fp_line
			(start 0.7874 0.4064)
			(end -0.7874 0.4064)
			(stroke
				(width 0.1524)
				(type default)
			)
			(layer "F.SilkS")
		)
		(fp_line
			(start 0.7874 -0.4064)
			(end 0.7874 0.4064)
			(stroke
				(width 0.1524)
				(type default)
			)
			(layer "F.SilkS")
		)
		(fp_line
			(start -0.7874 0.4064)
			(end -0.7874 -0.4064)
			(stroke
				(width 0.1524)
				(type default)
			)
			(layer "F.SilkS")
		)
		(fp_line
			(start -0.7874 -0.4064)
			(end 0.7874 -0.4064)
			(stroke
				(width 0.1524)
				(type default)
			)
			(layer "F.SilkS")
		)
		(fp_line
			(start 0.67945 0.3048)
			(end 0.120396 0.3048)
			(stroke
				(width 0.1)
				(type default)
			)
			(layer "F.Fab")
		)
		(fp_line
			(start 0.67945 -0.3048)
			(end 0.67945 0.3048)
			(stroke
				(width 0.1)
				(type default)
			)
			(layer "F.Fab")
		)
		(fp_line
			(start 0.12065 -0.2794)
			(end 0.12065 -0.3048)
			(stroke
				(width 0.1)
				(type default)
			)
			(layer "F.Fab")
		)
		(fp_line
			(start 0.12065 -0.3048)
			(end 0.67945 -0.3048)
			(stroke
				(width 0.1)
				(type default)
			)
			(layer "F.Fab")
		)
		(fp_line
			(start 0.120396 0.3048)
			(end 0.120396 0.2794)
			(stroke
				(width 0.1)
				(type default)
			)
			(layer "F.Fab")
		)
		(fp_line
			(start 0.120396 0.2794)
			(end -0.12065 0.2794)
			(stroke
				(width 0.1)
				(type default)
			)
			(layer "F.Fab")
		)
		(fp_line
			(start -0.12065 0.3048)
			(end -0.67945 0.3048)
			(stroke
				(width 0.1)
				(type default)
			)
			(layer "F.Fab")
		)
		(fp_line
			(start -0.12065 0.2794)
			(end -0.12065 0.3048)
			(stroke
				(width 0.1)
				(type default)
			)
			(layer "F.Fab")
		)
		(fp_line
			(start -0.12065 -0.2794)
			(end 0.12065 -0.2794)
			(stroke
				(width 0.1)
				(type default)
			)
			(layer "F.Fab")
		)
		(fp_line
			(start -0.12065 -0.305054)
			(end -0.12065 -0.2794)
			(stroke
				(width 0.1)
				(type default)
			)
			(layer "F.Fab")
		)
		(fp_line
			(start -0.67945 0.3048)
			(end -0.67945 -0.305054)
			(stroke
				(width 0.1)
				(type default)
			)
			(layer "F.Fab")
		)
		(fp_line
			(start -0.67945 -0.305054)
			(end -0.12065 -0.305054)
			(stroke
				(width 0.1)
				(type default)
			)
			(layer "F.Fab")
		)
		(pad "1" smd circle
			(at -0.40005 0 180)
			(size 0 0)
			(layers "F.Cu" "F.Mask" "F.Paste")
			(net "GND")
		)
		(pad "2" smd circle
			(at 0.40005 0 180)
			(size 0 0)
			(layers "F.Cu" "F.Mask" "F.Paste")
			(net "P12V_NIC1_CO_EN")
		)
	)
	(footprint ""
		(layer "F.Cu")
		(at 268.232382 -334.16367)
		(property "Reference" "R6797"
			(at 0 0 0)
			(layer "F.SilkS")
			(hide yes)
			(effects
				(font
					(size 1.27 1.27)
				)
			)
		)
		(property "Value" ""
			(at 0 0 0)
			(layer "F.Fab")
			(effects
				(font
					(size 1.27 1.27)
				)
			)
		)
		(duplicate_pad_numbers_are_jumpers no)
		(fp_line
			(start -0.7874 -0.4064)
			(end 0.7874 -0.4064)
			(stroke
				(width 0.1524)
				(type default)
			)
			(layer "F.SilkS")
		)
		(fp_line
			(start -0.7874 0.4064)
			(end -0.7874 -0.4064)
			(stroke
				(width 0.1524)
				(type default)
			)
			(layer "F.SilkS")
		)
		(fp_line
			(start 0.7874 -0.4064)
			(end 0.7874 0.4064)
			(stroke
				(width 0.1524)
				(type default)
			)
			(layer "F.SilkS")
		)
		(fp_line
			(start 0.7874 0.4064)
			(end -0.7874 0.4064)
			(stroke
				(width 0.1524)
				(type default)
			)
			(layer "F.SilkS")
		)
		(fp_line
			(start -0.67945 -0.305054)
			(end -0.12065 -0.305054)
			(stroke
				(width 0.1)
				(type default)
			)
			(layer "F.Fab")
		)
		(fp_line
			(start -0.67945 0.3048)
			(end -0.67945 -0.305054)
			(stroke
				(width 0.1)
				(type default)
			)
			(layer "F.Fab")
		)
		(fp_line
			(start -0.12065 -0.305054)
			(end -0.12065 -0.2794)
			(stroke
				(width 0.1)
				(type default)
			)
			(layer "F.Fab")
		)
		(fp_line
			(start -0.12065 -0.2794)
			(end 0.12065 -0.2794)
			(stroke
				(width 0.1)
				(type default)
			)
			(layer "F.Fab")
		)
		(fp_line
			(start -0.12065 0.2794)
			(end -0.12065 0.3048)
			(stroke
				(width 0.1)
				(type default)
			)
			(layer "F.Fab")
		)
		(fp_line
			(start -0.12065 0.3048)
			(end -0.67945 0.3048)
			(stroke
				(width 0.1)
				(type default)
			)
			(layer "F.Fab")
		)
		(fp_line
			(start 0.120396 0.2794)
			(end -0.12065 0.2794)
			(stroke
				(width 0.1)
				(type default)
			)
			(layer "F.Fab")
		)
		(fp_line
			(start 0.120396 0.3048)
			(end 0.120396 0.2794)
			(stroke
				(width 0.1)
				(type default)
			)
			(layer "F.Fab")
		)
		(fp_line
			(start 0.12065 -0.3048)
			(end 0.67945 -0.3048)
			(stroke
				(width 0.1)
				(type default)
			)
			(layer "F.Fab")
		)
		(fp_line
			(start 0.12065 -0.2794)
			(end 0.12065 -0.3048)
			(stroke
				(width 0.1)
				(type default)
			)
			(layer "F.Fab")
		)
		(fp_line
			(start 0.67945 -0.3048)
			(end 0.67945 0.3048)
			(stroke
				(width 0.1)
				(type default)
			)
			(layer "F.Fab")
		)
		(fp_line
			(start 0.67945 0.3048)
			(end 0.120396 0.3048)
			(stroke
				(width 0.1)
				(type default)
			)
			(layer "F.Fab")
		)
		(pad "1" smd circle
			(at -0.40005 0)
			(size 0 0)
			(layers "F.Cu" "F.Mask" "F.Paste")
			(net "HSC_D_OC_R2")
		)
		(pad "2" smd circle
			(at 0.40005 0)
			(size 0 0)
			(layers "F.Cu" "F.Mask" "F.Paste")
			(net "A_HSC_LOW_GATE")
		)
	)
	(footprint ""
		(layer "F.Cu")
		(at 80.019398 -149.79015 180)
		(property "Reference" "C8"
			(at 0 0 180)
			(layer "F.SilkS")
			(hide yes)
			(effects
				(font
					(size 1.27 1.27)
				)
			)
		)
		(property "Value" ""
			(at 0 0 180)
			(layer "F.Fab")
			(effects
				(font
					(size 1.27 1.27)
				)
			)
		)
		(duplicate_pad_numbers_are_jumpers no)
		(fp_line
			(start 0.299974 0.150114)
			(end -0.299974 0.150114)
			(stroke
				(width 0.1)
				(type default)
			)
			(layer "F.Fab")
		)
		(fp_line
			(start 0.299974 -0.150114)
			(end 0.299974 0.150114)
			(stroke
				(width 0.1)
				(type default)
			)
			(layer "F.Fab")
		)
		(fp_line
			(start -0.299974 0.150114)
			(end -0.299974 -0.150114)
			(stroke
				(width 0.1)
				(type default)
			)
			(layer "F.Fab")
		)
		(fp_line
			(start -0.299974 -0.150114)
			(end 0.299974 -0.150114)
			(stroke
				(width 0.1)
				(type default)
			)
			(layer "F.Fab")
		)
		(pad "1" smd rect
			(at -0.2667 0 180)
			(size 0.3048 0.381)
			(layers "F.Cu" "F.Mask" "F.Paste")
			(net "P5E_PEX0_STN0_TX_DP<12>")
		)
		(pad "2" smd rect
			(at 0.2667 0 180)
			(size 0.3048 0.381)
			(layers "F.Cu" "F.Mask" "F.Paste")
			(net "P5E_PEX0_STN0_TX_C_DP<12>")
		)
	)
	(footprint ""
		(layer "F.Cu")
		(at 71.247 -220.297756 90)
		(property "Reference" "R6634"
			(at 0 0 90)
			(layer "F.SilkS")
			(hide yes)
			(effects
				(font
					(size 1.27 1.27)
				)
			)
		)
		(property "Value" ""
			(at 0 0 90)
			(layer "F.Fab")
			(effects
				(font
					(size 1.27 1.27)
				)
			)
		)
		(duplicate_pad_numbers_are_jumpers no)
		(fp_line
			(start 0.7874 -0.4064)
			(end 0.7874 0.4064)
			(stroke
				(width 0.1524)
				(type default)
			)
			(layer "F.SilkS")
		)
		(fp_line
			(start -0.7874 -0.4064)
			(end 0.7874 -0.4064)
			(stroke
				(width 0.1524)
				(type default)
			)
			(layer "F.SilkS")
		)
		(fp_line
			(start 0.7874 0.4064)
			(end -0.7874 0.4064)
			(stroke
				(width 0.1524)
				(type default)
			)
			(layer "F.SilkS")
		)
		(fp_line
			(start -0.7874 0.4064)
			(end -0.7874 -0.4064)
			(stroke
				(width 0.1524)
				(type default)
			)
			(layer "F.SilkS")
		)
		(fp_line
			(start -0.12065 -0.305054)
			(end -0.12065 -0.2794)
			(stroke
				(width 0.1)
				(type default)
			)
			(layer "F.Fab")
		)
		(fp_line
			(start -0.67945 -0.305054)
			(end -0.12065 -0.305054)
			(stroke
				(width 0.1)
				(type default)
			)
			(layer "F.Fab")
		)
		(fp_line
			(start 0.67945 -0.3048)
			(end 0.67945 0.3048)
			(stroke
				(width 0.1)
				(type default)
			)
			(layer "F.Fab")
		)
		(fp_line
			(start 0.12065 -0.3048)
			(end 0.67945 -0.3048)
			(stroke
				(width 0.1)
				(type default)
			)
			(layer "F.Fab")
		)
		(fp_line
			(start 0.12065 -0.2794)
			(end 0.12065 -0.3048)
			(stroke
				(width 0.1)
				(type default)
			)
			(layer "F.Fab")
		)
		(fp_line
			(start -0.12065 -0.2794)
			(end 0.12065 -0.2794)
			(stroke
				(width 0.1)
				(type default)
			)
			(layer "F.Fab")
		)
		(fp_line
			(start 0.120396 0.2794)
			(end -0.12065 0.2794)
			(stroke
				(width 0.1)
				(type default)
			)
			(layer "F.Fab")
		)
		(fp_line
			(start -0.12065 0.2794)
			(end -0.12065 0.3048)
			(stroke
				(width 0.1)
				(type default)
			)
			(layer "F.Fab")
		)
		(fp_line
			(start 0.67945 0.3048)
			(end 0.120396 0.3048)
			(stroke
				(width 0.1)
				(type default)
			)
			(layer "F.Fab")
		)
		(fp_line
			(start 0.120396 0.3048)
			(end 0.120396 0.2794)
			(stroke
				(width 0.1)
				(type default)
			)
			(layer "F.Fab")
		)
		(fp_line
			(start -0.12065 0.3048)
			(end -0.67945 0.3048)
			(stroke
				(width 0.1)
				(type default)
			)
			(layer "F.Fab")
		)
		(fp_line
			(start -0.67945 0.3048)
			(end -0.67945 -0.305054)
			(stroke
				(width 0.1)
				(type default)
			)
			(layer "F.Fab")
		)
		(pad "1" smd circle
			(at -0.40005 0 90)
			(size 0 0)
			(layers "F.Cu" "F.Mask" "F.Paste")
			(net "UART_PEX3_CLI_BUF_R_TX")
		)
		(pad "2" smd circle
			(at 0.40005 0 90)
			(size 0 0)
			(layers "F.Cu" "F.Mask" "F.Paste")
			(net "UART_PEX3_CLI_BUF_R1_TX")
		)
	)
)
